(kicad_pcb
	(version 20260206)
	(generator "pcbnew")
	(generator_version "10.0")
	(general
		(thickness 1.6)
		(legacy_teardrops no)
	)
	(paper "A4")
	(title_block
		(title "Bryce Canyon_R.DPB_16317-1_OCP.brd")
		(comment 1 "Bryce Canyon / footprints 1639-1645 of 2099")
	)
	(layers
		(0 "F.Cu" signal "TOP")
		(4 "In1.Cu" signal "L2GND")
		(6 "In2.Cu" signal "L3")
		(8 "In3.Cu" signal "L4VCC")
		(10 "In4.Cu" signal "L5VCC")
		(12 "In5.Cu" signal "L6")
		(14 "In6.Cu" signal "L7GND")
		(2 "B.Cu" signal "BOTTOM")
		(9 "F.Adhes" user "F.Adhesive")
		(11 "B.Adhes" user "B.Adhesive")
		(13 "F.Paste" user "Package Geometry/Pastemask Top")
		(15 "B.Paste" user "Package Geometry/Pastemask Bottom")
		(5 "F.SilkS" user "Ref Des/Silkscreen Top")
		(7 "B.SilkS" user "Ref Des/Silkscreen Bottom")
		(1 "F.Mask" user "Board Geometry/Soldermask Top")
		(3 "B.Mask" user "Board Geometry/Soldermask Bottom")
		(17 "Dwgs.User" user "User.Drawings")
		(19 "Cmts.User" user "User.Comments")
		(21 "Eco1.User" user "User.Eco1")
		(23 "Eco2.User" user "User.Eco2")
		(25 "Edge.Cuts" user "Board Geometry/Outline")
		(27 "Margin" user)
		(31 "F.CrtYd" user "Package Geometry/Place Bound Top")
		(29 "B.CrtYd" user "Package Geometry/Place Bound Bottom")
		(35 "F.Fab" user "Ref Des/Assembly Top")
		(33 "B.Fab" user "Ref Des/Assembly Bottom")
	)
	(footprint ""
		(layer "F.Cu")
		(at 221.996 -305.2826)
		(property "Reference" "Q268"
			(at 0 0 0)
			(layer "F.SilkS")
			(hide yes)
			(effects
				(font
					(size 1.27 1.27)
				)
			)
		)
		(property "Value" "2N7002K-2-GP"
			(at 0.127 -8.9662 0)
			(unlocked yes)
			(layer "F.Fab")
			(hide yes)
			(effects
				(font
					(size 1.016 1.016)
					(thickness 0.1524)
				)
			)
		)
		(property "Device Type" "SOT23DGS2D4H44"
			(at 0.127 -10.4902 0)
			(unlocked yes)
			(layer "F.Fab")
			(hide yes)
			(effects
				(font
					(size 1.016 1.016)
					(thickness 0.1524)
				)
			)
		)
		(duplicate_pad_numbers_are_jumpers no)
		(fp_line
			(start -1.651 -1.778)
			(end -1.651 1.778)
			(stroke
				(width 0.1524)
				(type default)
			)
			(layer "F.SilkS")
		)
		(fp_line
			(start -1.651 1.778)
			(end 1.651 1.778)
			(stroke
				(width 0.1524)
				(type default)
			)
			(layer "F.SilkS")
		)
		(fp_line
			(start 1.651 -1.778)
			(end -1.651 -1.778)
			(stroke
				(width 0.1524)
				(type default)
			)
			(layer "F.SilkS")
		)
		(fp_line
			(start 1.651 1.778)
			(end 1.651 -1.778)
			(stroke
				(width 0.1524)
				(type default)
			)
			(layer "F.SilkS")
		)
		(fp_poly
			(pts
				(xy -1.778 1.8796) (xy -1.778 -1.8796) (xy 1.778 -1.8796) (xy 1.778 1.8796)
			)
			(stroke
				(width 0)
				(type default)
			)
			(fill no)
			(layer "F.CrtYd")
		)
		(fp_poly
			(pts
				(xy -1.778 1.8796) (xy -1.778 -1.8796) (xy 1.778 -1.8796) (xy 1.778 1.8796)
			)
			(stroke
				(width 0)
				(type default)
			)
			(fill no)
			(layer "F.Fab")
		)
		(pad "D" smd custom
			(at 0 -0.9525)
			(size 0.1905 0.1905)
			(layers "F.Cu" "F.Mask" "F.Paste")
			(net "FANTACH_A_OE_N")
			(options
				(clearance outline)
				(anchor circle)
			)
			(primitives
				(gr_poly
					(pts
						(arc
							(start -0.1778 0.5715)
							(mid -0.321484 0.511984)
							(end -0.381 0.3683)
						)
						(arc
							(start -0.381 -0.3683)
							(mid -0.321484 -0.511984)
							(end -0.1778 -0.5715)
						)
						(arc
							(start 0.1778 -0.5715)
							(mid 0.321484 -0.511984)
							(end 0.381 -0.3683)
						)
						(arc
							(start 0.381 0.3683)
							(mid 0.321484 0.511984)
							(end 0.1778 0.5715)
						)
					)
					(width 0)
					(fill yes)
				)
			)
		)
		(pad "G" smd custom
			(at -0.98425 0.9525)
			(size 0.1905 0.1905)
			(layers "F.Cu" "F.Mask" "F.Paste")
			(net "FANTACH_A_OE")
			(options
				(clearance outline)
				(anchor circle)
			)
			(primitives
				(gr_poly
					(pts
						(arc
							(start -0.1778 0.5715)
							(mid -0.321484 0.511984)
							(end -0.381 0.3683)
						)
						(arc
							(start -0.381 -0.3683)
							(mid -0.321484 -0.511984)
							(end -0.1778 -0.5715)
						)
						(arc
							(start 0.1778 -0.5715)
							(mid 0.321484 -0.511984)
							(end 0.381 -0.3683)
						)
						(arc
							(start 0.381 0.3683)
							(mid 0.321484 0.511984)
							(end 0.1778 0.5715)
						)
					)
					(width 0)
					(fill yes)
				)
			)
		)
		(pad "S" smd custom
			(at 0.98425 0.9525)
			(size 0.1905 0.1905)
			(layers "F.Cu" "F.Mask" "F.Paste")
			(net "GND")
			(options
				(clearance outline)
				(anchor circle)
			)
			(primitives
				(gr_poly
					(pts
						(arc
							(start -0.1778 0.5715)
							(mid -0.321484 0.511984)
							(end -0.381 0.3683)
						)
						(arc
							(start -0.381 -0.3683)
							(mid -0.321484 -0.511984)
							(end -0.1778 -0.5715)
						)
						(arc
							(start 0.1778 -0.5715)
							(mid 0.321484 -0.511984)
							(end 0.381 -0.3683)
						)
						(arc
							(start 0.381 0.3683)
							(mid 0.321484 0.511984)
							(end 0.1778 0.5715)
						)
					)
					(width 0)
					(fill yes)
				)
			)
		)
	)
	(footprint ""
		(layer "F.Cu")
		(at 479.034602 -272.309844)
		(property "Reference" "C179"
			(at 0 0 0)
			(layer "F.SilkS")
			(hide yes)
			(effects
				(font
					(size 1.27 1.27)
				)
			)
		)
		(property "Value" "SC4D7U25V5KX-1-GP"
			(at -0.0762 -6.1214 0)
			(unlocked yes)
			(layer "F.Fab")
			(hide yes)
			(effects
				(font
					(size 1.016 1.016)
					(thickness 0.1524)
				)
			)
		)
		(property "Device Type" "C805H58"
			(at -0.0762 -8.1534 0)
			(unlocked yes)
			(layer "F.Fab")
			(hide yes)
			(effects
				(font
					(size 1.016 1.016)
					(thickness 0.1524)
				)
			)
		)
		(duplicate_pad_numbers_are_jumpers no)
		(fp_line
			(start 0.635 0)
			(end -0.635 0)
			(stroke
				(width 0.508)
				(type default)
			)
			(layer "F.SilkS")
		)
		(fp_rect
			(start -0.9652 1.778)
			(end 0.9652 -1.778)
			(stroke
				(width 0)
				(type default)
			)
			(fill no)
			(layer "F.CrtYd")
		)
		(fp_poly
			(pts
				(xy -0.9652 -1.778) (xy 0.9652 -1.778) (xy 0.9652 1.778) (xy -0.9652 1.778)
			)
			(stroke
				(width 0)
				(type default)
			)
			(fill no)
			(layer "F.Fab")
		)
		(pad "1" smd rect
			(at 0 -0.9652)
			(size 1.397 1.143)
			(layers "F.Cu" "F.Mask" "F.Paste")
			(net "P12V_HDD11")
		)
		(pad "2" smd rect
			(at 0 0.9652)
			(size 1.397 1.143)
			(layers "F.Cu" "F.Mask" "F.Paste")
			(net "GND")
		)
	)
	(footprint ""
		(layer "F.Cu")
		(at 133.7818 -367.8174 -90)
		(property "Reference" "C528"
			(at 0 0 270)
			(layer "F.SilkS")
			(hide yes)
			(effects
				(font
					(size 1.27 1.27)
				)
			)
		)
		(property "Value" "SCD1U25V2KX-2-GP"
			(at 1.1811 -2.7051 270)
			(unlocked yes)
			(layer "F.Fab")
			(hide yes)
			(effects
				(font
					(size 1.016 1.016)
					(thickness 0.1524)
				)
			)
		)
		(property "Device Type" "C402H22"
			(at 1.1811 -4.2291 270)
			(unlocked yes)
			(layer "F.Fab")
			(hide yes)
			(effects
				(font
					(size 1.016 1.016)
					(thickness 0.1524)
				)
			)
		)
		(duplicate_pad_numbers_are_jumpers no)
		(fp_rect
			(start -0.4318 0.9525)
			(end 0.4318 -0.9525)
			(stroke
				(width 0)
				(type default)
			)
			(fill no)
			(layer "F.CrtYd")
		)
		(fp_rect
			(start -0.4318 0.9525)
			(end 0.4318 -0.9525)
			(stroke
				(width 0)
				(type default)
			)
			(fill no)
			(layer "F.Fab")
		)
		(pad "1" smd custom
			(at 0 -0.4445 270)
			(size 0.1524 0.1524)
			(layers "F.Cu" "F.Mask" "F.Paste")
			(net "FAN_1_TACH1")
			(options
				(clearance outline)
				(anchor circle)
			)
			(primitives
				(gr_poly
					(pts
						(arc
							(start 0.3048 -0.2032)
							(mid 0.275042 -0.275042)
							(end 0.2032 -0.3048)
						)
						(arc
							(start -0.2032 -0.3048)
							(mid -0.275042 -0.275042)
							(end -0.3048 -0.2032)
						)
						(arc
							(start -0.3048 0.2032)
							(mid -0.275042 0.275042)
							(end -0.2032 0.3048)
						)
						(arc
							(start 0.2032 0.3048)
							(mid 0.275042 0.275042)
							(end 0.3048 0.2032)
						)
					)
					(width 0)
					(fill yes)
				)
			)
		)
		(pad "2" smd custom
			(at 0 0.4445 270)
			(size 0.1524 0.1524)
			(layers "F.Cu" "F.Mask" "F.Paste")
			(net "GND")
			(options
				(clearance outline)
				(anchor circle)
			)
			(primitives
				(gr_poly
					(pts
						(arc
							(start 0.3048 -0.2032)
							(mid 0.275042 -0.275042)
							(end 0.2032 -0.3048)
						)
						(arc
							(start -0.2032 -0.3048)
							(mid -0.275042 -0.275042)
							(end -0.3048 -0.2032)
						)
						(arc
							(start -0.3048 0.2032)
							(mid -0.275042 0.275042)
							(end -0.2032 0.3048)
						)
						(arc
							(start 0.2032 0.3048)
							(mid 0.275042 0.275042)
							(end 0.3048 0.2032)
						)
					)
					(width 0)
					(fill yes)
				)
			)
		)
	)
	(footprint ""
		(layer "F.Cu")
		(at 409.800044 -180.399944)
		(property "Reference" "LED10"
			(at 0 0 0)
			(layer "F.SilkS")
			(hide yes)
			(effects
				(font
					(size 1.27 1.27)
				)
			)
		)
		(property "Value" "LED-BY-19-GP"
			(at -2.132076 1.414018 0)
			(unlocked yes)
			(layer "F.Fab")
			(hide yes)
			(effects
				(font
					(size 1.016 1.016)
					(thickness 0.1524)
				)
			)
		)
		(property "Device Type" "LED-1615-4PH26"
			(at -2.132076 -0.109982 0)
			(unlocked yes)
			(layer "F.Fab")
			(hide yes)
			(effects
				(font
					(size 1.016 1.016)
					(thickness 0.1524)
				)
			)
		)
		(duplicate_pad_numbers_are_jumpers no)
		(fp_line
			(start -1.2954 0.254)
			(end -1.2954 1.6002)
			(stroke
				(width 0.508)
				(type default)
			)
			(layer "F.SilkS")
		)
		(fp_line
			(start -1.2954 1.6002)
			(end 1.2954 1.6002)
			(stroke
				(width 0.508)
				(type default)
			)
			(layer "F.SilkS")
		)
		(fp_line
			(start -1.1176 -1.4224)
			(end 1.1176 -1.4224)
			(stroke
				(width 0.1524)
				(type default)
			)
			(layer "F.SilkS")
		)
		(fp_line
			(start -1.1176 1.4224)
			(end -1.1176 -1.4224)
			(stroke
				(width 0.1524)
				(type default)
			)
			(layer "F.SilkS")
		)
		(fp_line
			(start 1.1176 -1.4224)
			(end 1.1176 1.4224)
			(stroke
				(width 0.1524)
				(type default)
			)
			(layer "F.SilkS")
		)
		(fp_line
			(start 1.1176 1.4224)
			(end -1.1176 1.4224)
			(stroke
				(width 0.1524)
				(type default)
			)
			(layer "F.SilkS")
		)
		(fp_line
			(start 1.2954 1.6002)
			(end 1.2954 0.254)
			(stroke
				(width 0.508)
				(type default)
			)
			(layer "F.SilkS")
		)
		(fp_rect
			(start -0.7493 0.8001)
			(end 0.7493 -0.8001)
			(stroke
				(width 0)
				(type default)
			)
			(fill no)
			(layer "F.CrtYd")
		)
		(fp_poly
			(pts
				(xy -1.3716 1.6764) (xy -1.3716 -1.6764) (xy 1.3716 -1.6764) (xy 1.3716 0.0635) (xy 0.7493 0.0635)
				(xy 0.7493 -0.8001) (xy -0.7493 -0.8001) (xy -0.7493 0.8001) (xy 0.7493 0.8001) (xy 0.7493 0.0762)
				(xy 1.3716 0.0762) (xy 1.3716 1.6764)
			)
			(stroke
				(width 0)
				(type default)
			)
			(fill no)
			(layer "F.CrtYd")
		)
		(fp_rect
			(start -1.3716 1.6764)
			(end 1.3716 -1.6764)
			(stroke
				(width 0)
				(type default)
			)
			(fill no)
			(layer "F.Fab")
		)
		(pad "1" smd rect
			(at 0.50038 -0.73025)
			(size 0.7112 0.8636)
			(layers "F.Cu" "F.Mask" "F.Paste")
			(net "DRV_ACT_9")
		)
		(pad "2" smd rect
			(at -0.50038 -0.73025)
			(size 0.7112 0.8636)
			(layers "F.Cu" "F.Mask" "F.Paste")
			(net "FLT_HDD9")
		)
		(pad "3" smd rect
			(at 0.50038 0.73025)
			(size 0.7112 0.8636)
			(layers "F.Cu" "F.Mask" "F.Paste")
			(net "DRV_ACT_9_N")
		)
		(pad "4" smd rect
			(at -0.50038 0.73025)
			(size 0.7112 0.8636)
			(layers "F.Cu" "F.Mask" "F.Paste")
			(net "FLT_HDD9_N")
		)
	)
	(footprint ""
		(layer "F.Cu")
		(at 261.5184 -217.2462)
		(property "Reference" "R126"
			(at 0 0 0)
			(layer "F.SilkS")
			(hide yes)
			(effects
				(font
					(size 1.27 1.27)
				)
			)
		)
		(property "Value" "4K7R2F-GP"
			(at 0.064008 -3.993896 0)
			(unlocked yes)
			(layer "F.Fab")
			(hide yes)
			(effects
				(font
					(size 1.016 1.016)
					(thickness 0.1524)
				)
			)
		)
		(property "Device Type" "R402H16"
			(at 0.064008 -5.517896 0)
			(unlocked yes)
			(layer "F.Fab")
			(hide yes)
			(effects
				(font
					(size 1.016 1.016)
					(thickness 0.1524)
				)
			)
		)
		(duplicate_pad_numbers_are_jumpers no)
		(fp_line
			(start -0.508 -0.9398)
			(end -0.508 0.9398)
			(stroke
				(width 0.1524)
				(type default)
			)
			(layer "F.SilkS")
		)
		(fp_line
			(start 0.508 -0.9398)
			(end -0.508 -0.9398)
			(stroke
				(width 0.1524)
				(type default)
			)
			(layer "F.SilkS")
		)
		(fp_rect
			(start -0.508 0.9398)
			(end 0.508 -0.9398)
			(stroke
				(width 0)
				(type default)
			)
			(fill no)
			(layer "F.CrtYd")
		)
		(fp_rect
			(start -0.508 0.9398)
			(end 0.508 -0.9398)
			(stroke
				(width 0)
				(type default)
			)
			(fill no)
			(layer "F.Fab")
		)
		(pad "1" smd custom
			(at 0 -0.4445)
			(size 0.1397 0.1397)
			(layers "F.Cu" "F.Mask" "F.Paste")
			(net "VOL_SEN_ADDR0")
			(options
				(clearance outline)
				(anchor circle)
			)
			(primitives
				(gr_poly
					(pts
						(arc
							(start -0.1778 -0.2794)
							(mid -0.249642 -0.249642)
							(end -0.2794 -0.1778)
						)
						(arc
							(start -0.2794 0.1778)
							(mid -0.249642 0.249642)
							(end -0.1778 0.2794)
						)
						(arc
							(start 0.1778 0.2794)
							(mid 0.249642 0.249642)
							(end 0.2794 0.1778)
						)
						(arc
							(start 0.2794 -0.1778)
							(mid 0.249642 -0.249642)
							(end 0.1778 -0.2794)
						)
					)
					(width 0)
					(fill yes)
				)
			)
		)
		(pad "2" smd custom
			(at 0 0.4445)
			(size 0.1397 0.1397)
			(layers "F.Cu" "F.Mask" "F.Paste")
			(net "GND")
			(options
				(clearance outline)
				(anchor circle)
			)
			(primitives
				(gr_poly
					(pts
						(arc
							(start -0.1778 -0.2794)
							(mid -0.249642 -0.249642)
							(end -0.2794 -0.1778)
						)
						(arc
							(start -0.2794 0.1778)
							(mid -0.249642 0.249642)
							(end -0.1778 0.2794)
						)
						(arc
							(start 0.1778 0.2794)
							(mid 0.249642 0.249642)
							(end 0.2794 0.1778)
						)
						(arc
							(start 0.2794 -0.1778)
							(mid 0.249642 -0.249642)
							(end 0.1778 -0.2794)
						)
					)
					(width 0)
					(fill yes)
				)
			)
		)
	)
	(footprint ""
		(layer "F.Cu")
		(at 20.193 -33.782 -90)
		(property "Reference" "C342"
			(at 0 0 270)
			(layer "F.SilkS")
			(hide yes)
			(effects
				(font
					(size 1.27 1.27)
				)
			)
		)
		(property "Value" "SC1U16V3KX-5GP"
			(at 0 -2.8194 270)
			(unlocked yes)
			(layer "F.Fab")
			(hide yes)
			(effects
				(font
					(size 1.016 1.016)
					(thickness 0.1524)
				)
			)
		)
		(property "Device Type" "C603H36"
			(at 0 -4.3434 270)
			(unlocked yes)
			(layer "F.Fab")
			(hide yes)
			(effects
				(font
					(size 1.016 1.016)
					(thickness 0.1524)
				)
			)
		)
		(duplicate_pad_numbers_are_jumpers no)
		(fp_line
			(start 0.508 0)
			(end -0.508 0)
			(stroke
				(width 0.2032)
				(type default)
			)
			(layer "F.SilkS")
		)
		(fp_rect
			(start -0.5842 1.3335)
			(end 0.5842 -1.3335)
			(stroke
				(width 0)
				(type default)
			)
			(fill no)
			(layer "F.CrtYd")
		)
		(fp_rect
			(start -0.5842 1.3335)
			(end 0.5842 -1.3335)
			(stroke
				(width 0)
				(type default)
			)
			(fill no)
			(layer "F.Fab")
		)
		(pad "1" smd custom
			(at 0 -0.762 270)
			(size 0.2159 0.2159)
			(layers "F.Cu" "F.Mask" "F.Paste")
			(net "P5V_HDD24")
			(options
				(clearance outline)
				(anchor circle)
			)
			(primitives
				(gr_poly
					(pts
						(arc
							(start -0.3302 -0.4318)
							(mid -0.402042 -0.402042)
							(end -0.4318 -0.3302)
						)
						(arc
							(start -0.4318 0.3302)
							(mid -0.402042 0.402042)
							(end -0.3302 0.4318)
						)
						(arc
							(start 0.3302 0.4318)
							(mid 0.402042 0.402042)
							(end 0.4318 0.3302)
						)
						(arc
							(start 0.4318 -0.3302)
							(mid 0.402042 -0.402042)
							(end 0.3302 -0.4318)
						)
					)
					(width 0)
					(fill yes)
				)
			)
		)
		(pad "2" smd custom
			(at 0 0.762 270)
			(size 0.2159 0.2159)
			(layers "F.Cu" "F.Mask" "F.Paste")
			(net "GND")
			(options
				(clearance outline)
				(anchor circle)
			)
			(primitives
				(gr_poly
					(pts
						(arc
							(start -0.3302 -0.4318)
							(mid -0.402042 -0.402042)
							(end -0.4318 -0.3302)
						)
						(arc
							(start -0.4318 0.3302)
							(mid -0.402042 0.402042)
							(end -0.3302 0.4318)
						)
						(arc
							(start 0.3302 0.4318)
							(mid 0.402042 0.402042)
							(end 0.4318 0.3302)
						)
						(arc
							(start 0.4318 -0.3302)
							(mid 0.402042 -0.402042)
							(end 0.3302 -0.4318)
						)
					)
					(width 0)
					(fill yes)
				)
			)
		)
	)
	(footprint ""
		(layer "F.Cu")
		(at 206.756 -338.582 90)
		(property "Reference" "R1016"
			(at 0 0 90)
			(layer "F.SilkS")
			(hide yes)
			(effects
				(font
					(size 1.27 1.27)
				)
			)
		)
		(property "Value" "10R5F-1-GP"
			(at 0 -8.9535 90)
			(unlocked yes)
			(layer "F.Fab")
			(hide yes)
			(effects
				(font
					(size 1.27 1.016)
					(thickness 0.1524)
				)
			)
		)
		(property "Device Type" "R805H24"
			(at 0 -10.6299 90)
			(unlocked yes)
			(layer "F.Fab")
			(hide yes)
			(effects
				(font
					(size 1.27 1.016)
					(thickness 0.1524)
				)
			)
		)
		(duplicate_pad_numbers_are_jumpers no)
		(fp_line
			(start 0.889 -1.7018)
			(end -0.889 -1.7018)
			(stroke
				(width 0.1524)
				(type default)
			)
			(layer "F.SilkS")
		)
		(fp_line
			(start 0.889 -1.7018)
			(end 0.889 -0.381)
			(stroke
				(width 0.1524)
				(type default)
			)
			(layer "F.SilkS")
		)
		(fp_line
			(start -0.889 -1.7018)
			(end -0.889 0.2794)
			(stroke
				(width 0.1524)
				(type default)
			)
			(layer "F.SilkS")
		)
		(fp_line
			(start -0.889 0.0762)
			(end -0.889 1.7018)
			(stroke
				(width 0.1524)
				(type default)
			)
			(layer "F.SilkS")
		)
		(fp_line
			(start 0.889 1.7018)
			(end 0.889 -0.508)
			(stroke
				(width 0.1524)
				(type default)
			)
			(layer "F.SilkS")
		)
		(fp_line
			(start -0.889 1.7018)
			(end 0.889 1.7018)
			(stroke
				(width 0.1524)
				(type default)
			)
			(layer "F.SilkS")
		)
		(fp_poly
			(pts
				(xy 0.9652 -1.778) (xy 0.9652 1.778) (xy -0.9652 1.778) (xy -0.9652 -1.778)
			)
			(stroke
				(width 0)
				(type default)
			)
			(fill no)
			(layer "F.CrtYd")
		)
		(fp_rect
			(start -0.9652 1.778)
			(end 0.9652 -1.778)
			(stroke
				(width 0)
				(type default)
			)
			(fill no)
			(layer "F.Fab")
		)
		(pad "1" smd rect
			(at 0 -0.9652 90)
			(size 1.397 1.143)
			(layers "F.Cu" "F.Mask" "F.Paste")
			(net "MB0_12V_CTRL_GATE2")
		)
		(pad "2" smd rect
			(at 0 0.9652 90)
			(size 1.397 1.143)
			(layers "F.Cu" "F.Mask" "F.Paste")
			(net "MB0_CM_GATE_R")
		)
	)
)
